(kicad_pcb
	(version 20260206)
	(generator "pcbnew")
	(generator_version "10.0")
	(general
		(thickness 1.6)
		(legacy_teardrops no)
	)
	(paper "A4")
	(title_block
		(title "Bryce Canyon_F.DPB_16315-1-OCP.brd")
		(comment 1 "Bryce Canyon / footprint 1370 of 2223 (MONO1), pads 74-146 of 166")
	)
	(layers
		(0 "F.Cu" signal "TOP")
		(4 "In1.Cu" signal "L2GND")
		(6 "In2.Cu" signal "L3")
		(8 "In3.Cu" signal "L4GND")
		(10 "In4.Cu" signal "L5")
		(12 "In5.Cu" signal "L6VCC")
		(14 "In6.Cu" signal "L7VCC")
		(16 "In7.Cu" signal "L8")
		(18 "In8.Cu" signal "L9GND")
		(20 "In9.Cu" signal "L10")
		(22 "In10.Cu" signal "L11GND")
		(2 "B.Cu" signal "BOTTOM")
		(9 "F.Adhes" user "F.Adhesive")
		(11 "B.Adhes" user "B.Adhesive")
		(13 "F.Paste" user "Package Geometry/Pastemask Top")
		(15 "B.Paste" user "Package Geometry/Pastemask Bottom")
		(5 "F.SilkS" user "Ref Des/Silkscreen Top")
		(7 "B.SilkS" user "Ref Des/Silkscreen Bottom")
		(1 "F.Mask" user "Board Geometry/Soldermask Top")
		(3 "B.Mask" user "Board Geometry/Soldermask Bottom")
		(17 "Dwgs.User" user "User.Drawings")
		(19 "Cmts.User" user "User.Comments")
		(21 "Eco1.User" user "User.Eco1")
		(23 "Eco2.User" user "User.Eco2")
		(25 "Edge.Cuts" user "Board Geometry/Outline")
		(27 "Margin" user)
		(31 "F.CrtYd" user "Package Geometry/Place Bound Top")
		(29 "B.CrtYd" user "Package Geometry/Place Bound Bottom")
		(35 "F.Fab" user "Ref Des/Assembly Top")
		(33 "B.Fab" user "Ref Des/Assembly Bottom")
	)
	(footprint ""
		(layer "F.Cu")
		(at 239.300004 -111.149892 90)
		(property "Reference" "MONO1"
			(at 0 0 90)
			(layer "F.SilkS")
			(hide yes)
			(effects
				(font
					(size 1.27 1.27)
				)
			)
		)
		(property "Value" "AMP-CONN164-4R-1-GP"
			(at -25.705054 -1.203706 90)
			(unlocked yes)
			(layer "F.Fab")
			(hide yes)
			(effects
				(font
					(size 1.016 1.016)
					(thickness 0.1524)
				)
			)
		)
		(property "Device Type" "PREFIT-164P-890091-1H441"
			(at -25.705054 -2.727706 90)
			(unlocked yes)
			(layer "F.Fab")
			(hide yes)
			(effects
				(font
					(size 1.016 1.016)
					(thickness 0.1524)
				)
			)
		)
		(duplicate_pad_numbers_are_jumpers no)
		(pad "A72" thru_hole circle
			(at 61.34989 -3.24993 90)
			(size 1.0668 1.0668)
			(drill 0.719836)
			(layers "*.Cu" "*.Mask")
			(remove_unused_layers no)
			(net "GND")
			(clearance 0.1905)
			(thermal_gap 0.1905)
		)
		(pad "A73" thru_hole circle
			(at 62.349888 -1.249934 90)
			(size 1.0668 1.0668)
			(drill 0.719836)
			(layers "*.Cu" "*.Mask")
			(remove_unused_layers no)
			(net "PCIE_IOM_A_TO_COMP_A_10_DP")
			(clearance 0.1905)
			(thermal_gap 0.1905)
		)
		(pad "A74" thru_hole circle
			(at 63.349886 -3.24993 90)
			(size 1.0668 1.0668)
			(drill 0.719836)
			(layers "*.Cu" "*.Mask")
			(remove_unused_layers no)
			(net "PCIE_IOM_A_TO_COMP_A_10_DN")
			(clearance 0.1905)
			(thermal_gap 0.1905)
		)
		(pad "A75" thru_hole circle
			(at 64.349884 -1.249934 90)
			(size 1.0668 1.0668)
			(drill 0.719836)
			(layers "*.Cu" "*.Mask")
			(remove_unused_layers no)
			(net "GND")
			(clearance 0.1905)
			(thermal_gap 0.1905)
		)
		(pad "A76" thru_hole circle
			(at 65.349882 -3.24993 90)
			(size 1.0668 1.0668)
			(drill 0.719836)
			(layers "*.Cu" "*.Mask")
			(remove_unused_layers no)
			(net "GND")
			(clearance 0.1905)
			(thermal_gap 0.1905)
		)
		(pad "A77" thru_hole circle
			(at 66.34988 -1.249934 90)
			(size 1.0668 1.0668)
			(drill 0.719836)
			(layers "*.Cu" "*.Mask")
			(remove_unused_layers no)
			(net "PCIE_IOM_A_TO_COMP_A_11_DP")
			(clearance 0.1905)
			(thermal_gap 0.1905)
		)
		(pad "A78" thru_hole circle
			(at 67.349878 -3.24993 90)
			(size 1.0668 1.0668)
			(drill 0.719836)
			(layers "*.Cu" "*.Mask")
			(remove_unused_layers no)
			(net "PCIE_IOM_A_TO_COMP_A_11_DN")
			(clearance 0.1905)
			(thermal_gap 0.1905)
		)
		(pad "A79" thru_hole circle
			(at 68.349876 -1.249934 90)
			(size 1.0668 1.0668)
			(drill 0.719836)
			(layers "*.Cu" "*.Mask")
			(remove_unused_layers no)
			(net "GND")
			(clearance 0.1905)
			(thermal_gap 0.1905)
		)
		(pad "A80" thru_hole circle
			(at 69.349874 -3.24993 90)
			(size 1.0668 1.0668)
			(drill 0.719836)
			(layers "*.Cu" "*.Mask")
			(remove_unused_layers no)
			(net "GND")
			(clearance 0.1905)
			(thermal_gap 0.1905)
		)
		(pad "A81" thru_hole circle
			(at 70.350126 -1.249934 90)
			(size 1.0668 1.0668)
			(drill 0.719836)
			(layers "*.Cu" "*.Mask")
			(remove_unused_layers no)
			(net "P12V_A_COMP")
			(clearance 0.1905)
			(thermal_gap 0.1905)
		)
		(pad "A82" thru_hole circle
			(at 71.350124 -3.24993 90)
			(size 1.0668 1.0668)
			(drill 0.719836)
			(layers "*.Cu" "*.Mask")
			(remove_unused_layers no)
			(net "P12V_A_COMP")
			(clearance 0.1905)
			(thermal_gap 0.1905)
		)
		(pad "B1" thru_hole circle
			(at -11.649964 1.249934 90)
			(size 1.0668 1.0668)
			(drill 0.719836)
			(layers "*.Cu" "*.Mask")
			(remove_unused_layers no)
			(net "P12V_A_COMP")
			(clearance 0.1905)
			(thermal_gap 0.1905)
		)
		(pad "B2" thru_hole circle
			(at -10.649966 3.24993 90)
			(size 1.0668 1.0668)
			(drill 0.719836)
			(layers "*.Cu" "*.Mask")
			(remove_unused_layers no)
			(net "P12V_A_COMP")
			(clearance 0.1905)
			(thermal_gap 0.1905)
		)
		(pad "B3" thru_hole circle
			(at -9.649968 1.249934 90)
			(size 1.0668 1.0668)
			(drill 0.719836)
			(layers "*.Cu" "*.Mask")
			(remove_unused_layers no)
			(net "P12V_A_COMP")
			(clearance 0.1905)
			(thermal_gap 0.1905)
		)
		(pad "B4" thru_hole circle
			(at -8.64997 3.24993 90)
			(size 1.0668 1.0668)
			(drill 0.719836)
			(layers "*.Cu" "*.Mask")
			(remove_unused_layers no)
			(net "GND")
			(clearance 0.1905)
			(thermal_gap 0.1905)
		)
		(pad "B5" thru_hole circle
			(at -7.649972 1.249934 90)
			(size 1.0668 1.0668)
			(drill 0.719836)
			(layers "*.Cu" "*.Mask")
			(remove_unused_layers no)
			(net "I2C_BMC_A_COMP_A_SCL")
			(clearance 0.1905)
			(thermal_gap 0.1905)
		)
		(pad "B6" thru_hole circle
			(at -6.649974 3.24993 90)
			(size 1.0668 1.0668)
			(drill 0.719836)
			(layers "*.Cu" "*.Mask")
			(remove_unused_layers no)
			(net "I2C_BMC_A_COMP_A_SDA")
			(clearance 0.1905)
			(thermal_gap 0.1905)
		)
		(pad "B7" thru_hole circle
			(at -5.649976 1.249934 90)
			(size 1.0668 1.0668)
			(drill 0.719836)
			(layers "*.Cu" "*.Mask")
			(remove_unused_layers no)
			(net "GND")
			(clearance 0.1905)
			(thermal_gap 0.1905)
		)
		(pad "B8" thru_hole circle
			(at -4.649978 3.24993 90)
			(size 1.0668 1.0668)
			(drill 0.719836)
			(layers "*.Cu" "*.Mask")
			(remove_unused_layers no)
			(net "COMP_A_PWR_BTN_N")
			(clearance 0.1905)
			(thermal_gap 0.1905)
		)
		(pad "B9" thru_hole circle
			(at -3.64998 1.249934 90)
			(size 1.0668 1.0668)
			(drill 0.719836)
			(layers "*.Cu" "*.Mask")
			(remove_unused_layers no)
			(net "USB_COMP_A_DP")
			(clearance 0.1905)
			(thermal_gap 0.1905)
		)
		(pad "B10" thru_hole circle
			(at -2.649982 3.24993 90)
			(size 1.0668 1.0668)
			(drill 0.719836)
			(layers "*.Cu" "*.Mask")
			(remove_unused_layers no)
			(net "USB_COMP_A_DN")
			(clearance 0.1905)
			(thermal_gap 0.1905)
		)
		(pad "B11" thru_hole circle
			(at -1.649984 1.249934 90)
			(size 1.0668 1.0668)
			(drill 0.719836)
			(layers "*.Cu" "*.Mask")
			(remove_unused_layers no)
			(net "SYS_A_RESET_BUFFER_N")
			(clearance 0.1905)
			(thermal_gap 0.1905)
		)
		(pad "B12" thru_hole circle
			(at 1.35001 3.24993 90)
			(size 1.0668 1.0668)
			(drill 0.719836)
			(layers "*.Cu" "*.Mask")
			(remove_unused_layers no)
			(net "COMP_A_BMC_A_ALERT_N")
			(clearance 0.1905)
			(thermal_gap 0.1905)
		)
		(pad "B13" thru_hole circle
			(at 2.350008 1.249934 90)
			(size 1.0668 1.0668)
			(drill 0.719836)
			(layers "*.Cu" "*.Mask")
			(remove_unused_layers no)
			(net "GND")
			(clearance 0.1905)
			(thermal_gap 0.1905)
		)
		(pad "B14" thru_hole circle
			(at 3.350006 3.24993 90)
			(size 1.0668 1.0668)
			(drill 0.719836)
			(layers "*.Cu" "*.Mask")
			(remove_unused_layers no)
			(net "GND")
			(clearance 0.1905)
			(thermal_gap 0.1905)
		)
		(pad "B15" thru_hole circle
			(at 4.350004 1.249934 90)
			(size 1.0668 1.0668)
			(drill 0.719836)
			(layers "*.Cu" "*.Mask")
			(remove_unused_layers no)
			(net "PCIE_COMP_A_TO_SCC_A_0_DP")
			(clearance 0.1905)
			(thermal_gap 0.1905)
		)
		(pad "B16" thru_hole circle
			(at 5.350002 3.24993 90)
			(size 1.0668 1.0668)
			(drill 0.719836)
			(layers "*.Cu" "*.Mask")
			(remove_unused_layers no)
			(net "PCIE_COMP_A_TO_SCC_A_0_DN")
			(clearance 0.1905)
			(thermal_gap 0.1905)
		)
		(pad "B17" thru_hole circle
			(at 6.35 1.249934 90)
			(size 1.0668 1.0668)
			(drill 0.719836)
			(layers "*.Cu" "*.Mask")
			(remove_unused_layers no)
			(net "GND")
			(clearance 0.1905)
			(thermal_gap 0.1905)
		)
		(pad "B18" thru_hole circle
			(at 7.349998 3.24993 90)
			(size 1.0668 1.0668)
			(drill 0.719836)
			(layers "*.Cu" "*.Mask")
			(remove_unused_layers no)
			(net "GND")
			(clearance 0.1905)
			(thermal_gap 0.1905)
		)
		(pad "B19" thru_hole circle
			(at 8.349996 1.249934 90)
			(size 1.0668 1.0668)
			(drill 0.719836)
			(layers "*.Cu" "*.Mask")
			(remove_unused_layers no)
			(net "PCIE_COMP_A_TO_SCC_A_1_DP")
			(clearance 0.1905)
			(thermal_gap 0.1905)
		)
		(pad "B20" thru_hole circle
			(at 9.349994 3.24993 90)
			(size 1.0668 1.0668)
			(drill 0.719836)
			(layers "*.Cu" "*.Mask")
			(remove_unused_layers no)
			(net "PCIE_COMP_A_TO_SCC_A_1_DN")
			(clearance 0.1905)
			(thermal_gap 0.1905)
		)
		(pad "B21" thru_hole circle
			(at 10.349992 1.249934 90)
			(size 1.0668 1.0668)
			(drill 0.719836)
			(layers "*.Cu" "*.Mask")
			(remove_unused_layers no)
			(net "GND")
			(clearance 0.1905)
			(thermal_gap 0.1905)
		)
		(pad "B22" thru_hole circle
			(at 11.34999 3.24993 90)
			(size 1.0668 1.0668)
			(drill 0.719836)
			(layers "*.Cu" "*.Mask")
			(remove_unused_layers no)
			(net "GND")
			(clearance 0.1905)
			(thermal_gap 0.1905)
		)
		(pad "B23" thru_hole circle
			(at 12.349988 1.249934 90)
			(size 1.0668 1.0668)
			(drill 0.719836)
			(layers "*.Cu" "*.Mask")
			(remove_unused_layers no)
			(net "PCIE_COMP_A_TO_SCC_A_2_DP")
			(clearance 0.1905)
			(thermal_gap 0.1905)
		)
		(pad "B24" thru_hole circle
			(at 13.349986 3.24993 90)
			(size 1.0668 1.0668)
			(drill 0.719836)
			(layers "*.Cu" "*.Mask")
			(remove_unused_layers no)
			(net "PCIE_COMP_A_TO_SCC_A_2_DN")
			(clearance 0.1905)
			(thermal_gap 0.1905)
		)
		(pad "B25" thru_hole circle
			(at 14.349984 1.249934 90)
			(size 1.0668 1.0668)
			(drill 0.719836)
			(layers "*.Cu" "*.Mask")
			(remove_unused_layers no)
			(net "GND")
			(clearance 0.1905)
			(thermal_gap 0.1905)
		)
		(pad "B26" thru_hole circle
			(at 15.349982 3.24993 90)
			(size 1.0668 1.0668)
			(drill 0.719836)
			(layers "*.Cu" "*.Mask")
			(remove_unused_layers no)
			(net "GND")
			(clearance 0.1905)
			(thermal_gap 0.1905)
		)
		(pad "B27" thru_hole circle
			(at 16.34998 1.249934 90)
			(size 1.0668 1.0668)
			(drill 0.719836)
			(layers "*.Cu" "*.Mask")
			(remove_unused_layers no)
			(net "PCIE_COMP_A_TO_SCC_A_3_DP")
			(clearance 0.1905)
			(thermal_gap 0.1905)
		)
		(pad "B28" thru_hole circle
			(at 17.349978 3.24993 90)
			(size 1.0668 1.0668)
			(drill 0.719836)
			(layers "*.Cu" "*.Mask")
			(remove_unused_layers no)
			(net "PCIE_COMP_A_TO_SCC_A_3_DN")
			(clearance 0.1905)
			(thermal_gap 0.1905)
		)
		(pad "B29" thru_hole circle
			(at 18.349976 1.249934 90)
			(size 1.0668 1.0668)
			(drill 0.719836)
			(layers "*.Cu" "*.Mask")
			(remove_unused_layers no)
			(net "GND")
			(clearance 0.1905)
			(thermal_gap 0.1905)
		)
		(pad "B30" thru_hole circle
			(at 19.349974 3.24993 90)
			(size 1.0668 1.0668)
			(drill 0.719836)
			(layers "*.Cu" "*.Mask")
			(remove_unused_layers no)
			(net "GND")
			(clearance 0.1905)
			(thermal_gap 0.1905)
		)
		(pad "B31" thru_hole circle
			(at 20.349972 1.249934 90)
			(size 1.0668 1.0668)
			(drill 0.719836)
			(layers "*.Cu" "*.Mask")
			(remove_unused_layers no)
			(net "TP_COMP_A_SATA_P0_TX_DP")
			(clearance 0.1905)
			(thermal_gap 0.1905)
		)
		(pad "B32" thru_hole circle
			(at 21.34997 3.24993 90)
			(size 1.0668 1.0668)
			(drill 0.719836)
			(layers "*.Cu" "*.Mask")
			(remove_unused_layers no)
			(net "TP_COMP_A_SATA_P0_TX_DN")
			(clearance 0.1905)
			(thermal_gap 0.1905)
		)
		(pad "B33" thru_hole circle
			(at 22.349968 1.249934 90)
			(size 1.0668 1.0668)
			(drill 0.719836)
			(layers "*.Cu" "*.Mask")
			(remove_unused_layers no)
			(net "GND")
			(clearance 0.1905)
			(thermal_gap 0.1905)
		)
		(pad "B34" thru_hole circle
			(at 23.349966 3.24993 90)
			(size 1.0668 1.0668)
			(drill 0.719836)
			(layers "*.Cu" "*.Mask")
			(remove_unused_layers no)
			(net "GND")
			(clearance 0.1905)
			(thermal_gap 0.1905)
		)
		(pad "B35" thru_hole circle
			(at 24.349964 1.249934 90)
			(size 1.0668 1.0668)
			(drill 0.719836)
			(layers "*.Cu" "*.Mask")
			(remove_unused_layers no)
			(net "TP_PCIE_COMP_A_CLK_1_DP")
			(clearance 0.1905)
			(thermal_gap 0.1905)
		)
		(pad "B36" thru_hole circle
			(at 25.349962 3.24993 90)
			(size 1.0668 1.0668)
			(drill 0.719836)
			(layers "*.Cu" "*.Mask")
			(remove_unused_layers no)
			(net "TP_PCIE_COMP_A_CLK_1_DN")
			(clearance 0.1905)
			(thermal_gap 0.1905)
		)
		(pad "B37" thru_hole circle
			(at 26.34996 1.249934 90)
			(size 1.0668 1.0668)
			(drill 0.719836)
			(layers "*.Cu" "*.Mask")
			(remove_unused_layers no)
			(net "GND")
			(clearance 0.1905)
			(thermal_gap 0.1905)
		)
		(pad "B38" thru_hole circle
			(at 27.349958 3.24993 90)
			(size 1.0668 1.0668)
			(drill 0.719836)
			(layers "*.Cu" "*.Mask")
			(remove_unused_layers no)
			(net "GND")
			(clearance 0.1905)
			(thermal_gap 0.1905)
		)
		(pad "B39" thru_hole circle
			(at 28.349956 1.249934 90)
			(size 1.0668 1.0668)
			(drill 0.719836)
			(layers "*.Cu" "*.Mask")
			(remove_unused_layers no)
			(net "PCIE_COMP_A_PCIE_RST_1")
			(clearance 0.1905)
			(thermal_gap 0.1905)
		)
		(pad "B40" thru_hole circle
			(at 29.349954 3.24993 90)
			(size 1.0668 1.0668)
			(drill 0.719836)
			(layers "*.Cu" "*.Mask")
			(remove_unused_layers no)
			(net "PCIE_COMP_A_TO_IOM_A_RST_2")
			(clearance 0.1905)
			(thermal_gap 0.1905)
		)
		(pad "B41" thru_hole circle
			(at 30.349952 1.249934 90)
			(size 1.0668 1.0668)
			(drill 0.719836)
			(layers "*.Cu" "*.Mask")
			(remove_unused_layers no)
			(net "GND")
			(clearance 0.1905)
			(thermal_gap 0.1905)
		)
		(pad "B42" thru_hole circle
			(at 31.34995 3.24993 90)
			(size 1.0668 1.0668)
			(drill 0.719836)
			(layers "*.Cu" "*.Mask")
			(remove_unused_layers no)
			(net "GND")
			(clearance 0.1905)
			(thermal_gap 0.1905)
		)
		(pad "B43" thru_hole circle
			(at 32.349948 1.249934 90)
			(size 1.0668 1.0668)
			(drill 0.719836)
			(layers "*.Cu" "*.Mask")
			(remove_unused_layers no)
			(net "TP_SMB_COMP_A_NIC_SCL")
			(clearance 0.1905)
			(thermal_gap 0.1905)
		)
		(pad "B44" thru_hole circle
			(at 33.349946 3.24993 90)
			(size 1.0668 1.0668)
			(drill 0.719836)
			(layers "*.Cu" "*.Mask")
			(remove_unused_layers no)
			(net "TP_SMB_COMP_A_NIC_SDA")
			(clearance 0.1905)
			(thermal_gap 0.1905)
		)
		(pad "B45" thru_hole circle
			(at 34.349944 1.249934 90)
			(size 1.0668 1.0668)
			(drill 0.719836)
			(layers "*.Cu" "*.Mask")
			(remove_unused_layers no)
			(net "GND")
			(clearance 0.1905)
			(thermal_gap 0.1905)
		)
		(pad "B46" thru_hole circle
			(at 35.349942 3.24993 90)
			(size 1.0668 1.0668)
			(drill 0.719836)
			(layers "*.Cu" "*.Mask")
			(remove_unused_layers no)
			(net "GND")
			(clearance 0.1905)
			(thermal_gap 0.1905)
		)
		(pad "B47" thru_hole circle
			(at 36.34994 1.249934 90)
			(size 1.0668 1.0668)
			(drill 0.719836)
			(layers "*.Cu" "*.Mask")
			(remove_unused_layers no)
			(net "TP_COMP_A_KR_P0_TX_DP")
			(clearance 0.1905)
			(thermal_gap 0.1905)
		)
		(pad "B48" thru_hole circle
			(at 37.349938 3.24993 90)
			(size 1.0668 1.0668)
			(drill 0.719836)
			(layers "*.Cu" "*.Mask")
			(remove_unused_layers no)
			(net "TP_COMP_A_KR_P0_TX_DN")
			(clearance 0.1905)
			(thermal_gap 0.1905)
		)
		(pad "B49" thru_hole circle
			(at 38.349936 1.249934 90)
			(size 1.0668 1.0668)
			(drill 0.719836)
			(layers "*.Cu" "*.Mask")
			(remove_unused_layers no)
			(net "GND")
			(clearance 0.1905)
			(thermal_gap 0.1905)
		)
		(pad "B50" thru_hole circle
			(at 39.349934 3.24993 90)
			(size 1.0668 1.0668)
			(drill 0.719836)
			(layers "*.Cu" "*.Mask")
			(remove_unused_layers no)
			(net "GND")
			(clearance 0.1905)
			(thermal_gap 0.1905)
		)
		(pad "B51" thru_hole circle
			(at 40.349932 1.249934 90)
			(size 1.0668 1.0668)
			(drill 0.719836)
			(layers "*.Cu" "*.Mask")
			(remove_unused_layers no)
			(net "PCIE_COMP_A_TO_SCC_A_4_DP")
			(clearance 0.1905)
			(thermal_gap 0.1905)
		)
		(pad "B52" thru_hole circle
			(at 41.34993 3.24993 90)
			(size 1.0668 1.0668)
			(drill 0.719836)
			(layers "*.Cu" "*.Mask")
			(remove_unused_layers no)
			(net "PCIE_COMP_A_TO_SCC_A_4_DN")
			(clearance 0.1905)
			(thermal_gap 0.1905)
		)
		(pad "B53" thru_hole circle
			(at 42.349928 1.249934 90)
			(size 1.0668 1.0668)
			(drill 0.719836)
			(layers "*.Cu" "*.Mask")
			(remove_unused_layers no)
			(net "GND")
			(clearance 0.1905)
			(thermal_gap 0.1905)
		)
		(pad "B54" thru_hole circle
			(at 43.349926 3.24993 90)
			(size 1.0668 1.0668)
			(drill 0.719836)
			(layers "*.Cu" "*.Mask")
			(remove_unused_layers no)
			(net "GND")
			(clearance 0.1905)
			(thermal_gap 0.1905)
		)
		(pad "B55" thru_hole circle
			(at 44.349924 1.249934 90)
			(size 1.0668 1.0668)
			(drill 0.719836)
			(layers "*.Cu" "*.Mask")
			(remove_unused_layers no)
			(net "PCIE_COMP_A_TO_SCC_A_5_DP")
			(clearance 0.1905)
			(thermal_gap 0.1905)
		)
		(pad "B56" thru_hole circle
			(at 45.349922 3.24993 90)
			(size 1.0668 1.0668)
			(drill 0.719836)
			(layers "*.Cu" "*.Mask")
			(remove_unused_layers no)
			(net "PCIE_COMP_A_TO_SCC_A_5_DN")
			(clearance 0.1905)
			(thermal_gap 0.1905)
		)
		(pad "B57" thru_hole circle
			(at 46.34992 1.249934 90)
			(size 1.0668 1.0668)
			(drill 0.719836)
			(layers "*.Cu" "*.Mask")
			(remove_unused_layers no)
			(net "GND")
			(clearance 0.1905)
			(thermal_gap 0.1905)
		)
		(pad "B58" thru_hole circle
			(at 47.349918 3.24993 90)
			(size 1.0668 1.0668)
			(drill 0.719836)
			(layers "*.Cu" "*.Mask")
			(remove_unused_layers no)
			(net "GND")
			(clearance 0.1905)
			(thermal_gap 0.1905)
		)
		(pad "B59" thru_hole circle
			(at 48.349916 1.249934 90)
			(size 1.0668 1.0668)
			(drill 0.719836)
			(layers "*.Cu" "*.Mask")
			(remove_unused_layers no)
			(net "PCIE_COMP_A_TO_SCC_A_6_DP")
			(clearance 0.1905)
			(thermal_gap 0.1905)
		)
		(pad "B60" thru_hole circle
			(at 49.349914 3.24993 90)
			(size 1.0668 1.0668)
			(drill 0.719836)
			(layers "*.Cu" "*.Mask")
			(remove_unused_layers no)
			(net "PCIE_COMP_A_TO_SCC_A_6_DN")
			(clearance 0.1905)
			(thermal_gap 0.1905)
		)
		(pad "B61" thru_hole circle
			(at 50.349912 1.249934 90)
			(size 1.0668 1.0668)
			(drill 0.719836)
			(layers "*.Cu" "*.Mask")
			(remove_unused_layers no)
			(net "GND")
			(clearance 0.1905)
			(thermal_gap 0.1905)
		)
		(pad "B62" thru_hole circle
			(at 51.34991 3.24993 90)
			(size 1.0668 1.0668)
			(drill 0.719836)
			(layers "*.Cu" "*.Mask")
			(remove_unused_layers no)
			(net "GND")
			(clearance 0.1905)
			(thermal_gap 0.1905)
		)
	)
)
